# S9S_MB_2U (Grand Teton) — schematic netlist excerpt (pin names and nets, part order shuffled) for the footprints in the layout excerpt that follows; sources: Cadence DE-HDL packaged netlist, KiCad conversion of 03242023_DA0F0TMBIJ0_F0T_Motherboard_J_brd_V01_OCP.brd

C2  Q_CAP  2.2UF 6.3V 20% X6S  pkg C0402  page 82 : A = P3V3_AUX ; B = GND
R1412  Q_RES  2K 1% CHIP  pkg 0402LF  page 219 : A = FM_PVCCFA_EHV_FIVRA_CPU1_R_EN ; B = GND

(kicad_pcb
	(version 20260206)
	(generator "pcbnew")
	(generator_version "10.0")
	(general
		(thickness 1.6)
		(legacy_teardrops no)
	)
	(paper "A4")
	(title_block
		(title "03242023_DA0F0TMBIJ0_F0T_Motherboard_J_brd_V01_OCP.brd")
		(comment 1 "Grand Teton / footprints 5444-5445 of 6105")
	)
	(layers
		(0 "F.Cu" signal "TOP")
		(4 "In1.Cu" signal "GND")
		(6 "In2.Cu" signal "IN1")
		(8 "In3.Cu" signal "GND1")
		(10 "In4.Cu" signal "IN2")
		(12 "In5.Cu" signal "GND2")
		(14 "In6.Cu" signal "IN3")
		(16 "In7.Cu" signal "GND3")
		(18 "In8.Cu" signal "VCC")
		(20 "In9.Cu" signal "VCC1")
		(22 "In10.Cu" signal "GND4")
		(24 "In11.Cu" signal "IN4")
		(26 "In12.Cu" signal "GND5")
		(28 "In13.Cu" signal "IN5")
		(30 "In14.Cu" signal "GND6")
		(32 "In15.Cu" signal "IN6")
		(34 "In16.Cu" signal "GND7")
		(2 "B.Cu" signal "BOTTOM")
		(9 "F.Adhes" user "F.Adhesive")
		(11 "B.Adhes" user "B.Adhesive")
		(13 "F.Paste" user "Package Geometry/Pastemask Top")
		(15 "B.Paste" user "Package Geometry/Pastemask Bottom")
		(5 "F.SilkS" user "Ref Des/Silkscreen Top")
		(7 "B.SilkS" user "Ref Des/Silkscreen Bottom")
		(1 "F.Mask" user "Board Geometry/Soldermask Top")
		(3 "B.Mask" user "Board Geometry/Soldermask Bottom")
		(17 "Dwgs.User" user "User.Drawings")
		(19 "Cmts.User" user "User.Comments")
		(21 "Eco1.User" user "User.Eco1")
		(23 "Eco2.User" user "User.Eco2")
		(25 "Edge.Cuts" user "Board Geometry/Outline")
		(27 "Margin" user)
		(31 "F.CrtYd" user "Package Geometry/Place Bound Top")
		(29 "B.CrtYd" user "Package Geometry/Place Bound Bottom")
		(35 "F.Fab" user "Ref Des/Assembly Top")
		(33 "B.Fab" user "Ref Des/Assembly Bottom")
	)
	(footprint ""
		(layer "B.Cu")
		(at 160.83788 -122.646948)
		(property "Reference" "R1412"
			(at 0 0 0)
			(layer "B.SilkS")
			(hide yes)
			(effects
				(font
					(size 1.27 1.27)
				)
				(justify mirror)
			)
		)
		(property "Value" ""
			(at 0 0 0)
			(layer "B.Fab")
			(effects
				(font
					(size 1.27 1.27)
				)
				(justify mirror)
			)
		)
		(duplicate_pad_numbers_are_jumpers no)
		(fp_line
			(start -0.7874 -0.4064)
			(end -0.7874 0.4064)
			(stroke
				(width 0.1524)
				(type default)
			)
			(layer "B.SilkS")
		)
		(fp_line
			(start -0.7874 0.4064)
			(end 0.7874 0.4064)
			(stroke
				(width 0.1524)
				(type default)
			)
			(layer "B.SilkS")
		)
		(fp_line
			(start 0.7874 -0.4064)
			(end -0.7874 -0.4064)
			(stroke
				(width 0.1524)
				(type default)
			)
			(layer "B.SilkS")
		)
		(fp_line
			(start 0.7874 0.4064)
			(end 0.7874 -0.4064)
			(stroke
				(width 0.1524)
				(type default)
			)
			(layer "B.SilkS")
		)
		(fp_line
			(start -0.67945 -0.3048)
			(end -0.67945 0.3048)
			(stroke
				(width 0.1)
				(type default)
			)
			(layer "B.Fab")
		)
		(fp_line
			(start -0.67945 0.3048)
			(end -0.120396 0.3048)
			(stroke
				(width 0.1)
				(type default)
			)
			(layer "B.Fab")
		)
		(fp_line
			(start -0.12065 -0.3048)
			(end -0.67945 -0.3048)
			(stroke
				(width 0.1)
				(type default)
			)
			(layer "B.Fab")
		)
		(fp_line
			(start -0.12065 -0.2794)
			(end -0.12065 -0.3048)
			(stroke
				(width 0.1)
				(type default)
			)
			(layer "B.Fab")
		)
		(fp_line
			(start -0.120396 0.2794)
			(end 0.12065 0.2794)
			(stroke
				(width 0.1)
				(type default)
			)
			(layer "B.Fab")
		)
		(fp_line
			(start -0.120396 0.3048)
			(end -0.120396 0.2794)
			(stroke
				(width 0.1)
				(type default)
			)
			(layer "B.Fab")
		)
		(fp_line
			(start 0.12065 -0.305054)
			(end 0.12065 -0.2794)
			(stroke
				(width 0.1)
				(type default)
			)
			(layer "B.Fab")
		)
		(fp_line
			(start 0.12065 -0.2794)
			(end -0.12065 -0.2794)
			(stroke
				(width 0.1)
				(type default)
			)
			(layer "B.Fab")
		)
		(fp_line
			(start 0.12065 0.2794)
			(end 0.12065 0.3048)
			(stroke
				(width 0.1)
				(type default)
			)
			(layer "B.Fab")
		)
		(fp_line
			(start 0.12065 0.3048)
			(end 0.67945 0.3048)
			(stroke
				(width 0.1)
				(type default)
			)
			(layer "B.Fab")
		)
		(fp_line
			(start 0.67945 -0.305054)
			(end 0.12065 -0.305054)
			(stroke
				(width 0.1)
				(type default)
			)
			(layer "B.Fab")
		)
		(fp_line
			(start 0.67945 0.3048)
			(end 0.67945 -0.305054)
			(stroke
				(width 0.1)
				(type default)
			)
			(layer "B.Fab")
		)
		(pad "1" smd circle
			(at 0.40005 0 180)
			(size 0 0)
			(layers "B.Cu" "B.Mask" "B.Paste")
			(net "FM_PVCCFA_EHV_FIVRA_CPU1_R_EN")
		)
		(pad "2" smd circle
			(at -0.40005 0 180)
			(size 0 0)
			(layers "B.Cu" "B.Mask" "B.Paste")
			(net "GND")
		)
	)
	(footprint ""
		(layer "B.Cu")
		(at 301.356014 -319.263776 180)
		(property "Reference" "C2"
			(at 0 0 0)
			(layer "B.SilkS")
			(hide yes)
			(effects
				(font
					(size 1.27 1.27)
				)
				(justify mirror)
			)
		)
		(property "Value" ""
			(at 0 0 0)
			(layer "B.Fab")
			(effects
				(font
					(size 1.27 1.27)
				)
				(justify mirror)
			)
		)
		(duplicate_pad_numbers_are_jumpers no)
		(fp_line
			(start 0.7874 0.4064)
			(end 0.7874 -0.4064)
			(stroke
				(width 0.1524)
				(type default)
			)
			(layer "B.SilkS")
		)
		(fp_line
			(start 0.7874 -0.4064)
			(end -0.7874 -0.4064)
			(stroke
				(width 0.1524)
				(type default)
			)
			(layer "B.SilkS")
		)
		(fp_line
			(start -0.7874 0.4064)
			(end 0.7874 0.4064)
			(stroke
				(width 0.1524)
				(type default)
			)
			(layer "B.SilkS")
		)
		(fp_line
			(start -0.7874 -0.4064)
			(end -0.7874 0.4064)
			(stroke
				(width 0.1524)
				(type default)
			)
			(layer "B.SilkS")
		)
		(fp_line
			(start 0.67945 0.3048)
			(end 0.67945 -0.305054)
			(stroke
				(width 0.1)
				(type default)
			)
			(layer "B.Fab")
		)
		(fp_line
			(start 0.67945 -0.305054)
			(end 0.12065 -0.305054)
			(stroke
				(width 0.1)
				(type default)
			)
			(layer "B.Fab")
		)
		(fp_line
			(start 0.12065 0.3048)
			(end 0.67945 0.3048)
			(stroke
				(width 0.1)
				(type default)
			)
			(layer "B.Fab")
		)
		(fp_line
			(start 0.12065 0.2794)
			(end 0.12065 0.3048)
			(stroke
				(width 0.1)
				(type default)
			)
			(layer "B.Fab")
		)
		(fp_line
			(start 0.12065 -0.2794)
			(end -0.12065 -0.2794)
			(stroke
				(width 0.1)
				(type default)
			)
			(layer "B.Fab")
		)
		(fp_line
			(start 0.12065 -0.305054)
			(end 0.12065 -0.2794)
			(stroke
				(width 0.1)
				(type default)
			)
			(layer "B.Fab")
		)
		(fp_line
			(start -0.120396 0.3048)
			(end -0.120396 0.2794)
			(stroke
				(width 0.1)
				(type default)
			)
			(layer "B.Fab")
		)
		(fp_line
			(start -0.120396 0.2794)
			(end 0.12065 0.2794)
			(stroke
				(width 0.1)
				(type default)
			)
			(layer "B.Fab")
		)
		(fp_line
			(start -0.12065 -0.2794)
			(end -0.12065 -0.3048)
			(stroke
				(width 0.1)
				(type default)
			)
			(layer "B.Fab")
		)
		(fp_line
			(start -0.12065 -0.3048)
			(end -0.67945 -0.3048)
			(stroke
				(width 0.1)
				(type default)
			)
			(layer "B.Fab")
		)
		(fp_line
			(start -0.67945 0.3048)
			(end -0.120396 0.3048)
			(stroke
				(width 0.1)
				(type default)
			)
			(layer "B.Fab")
		)
		(fp_line
			(start -0.67945 -0.3048)
			(end -0.67945 0.3048)
			(stroke
				(width 0.1)
				(type default)
			)
			(layer "B.Fab")
		)
		(pad "1" smd circle
			(at 0.40005 0)
			(size 0 0)
			(layers "B.Cu" "B.Mask" "B.Paste")
			(net "P3V3_AUX")
		)
		(pad "2" smd circle
			(at -0.40005 0)
			(size 0 0)
			(layers "B.Cu" "B.Mask" "B.Paste")
			(net "GND")
		)
	)
)
